G04 ================== begin FILE IDENTIFICATION RECORD ==================*
G04 Layout Name:  12523-1.brd*
G04 Film Name:    P_OUTLINE*
G04 File Format:  Gerber RS274X*
G04 File Origin:  Cadence Allegro 16.2-s031*
G04 Origin Date:  Fri Oct 19 14:59:04 2012*
G04 *
G04 Layer:  BOARD GEOMETRY/PANEL_OUTLINE*
G04 *
G04 Offset:    (0.00 0.00)*
G04 Mirror:    No*
G04 Mode:      Positive*
G04 Rotation:  0*
G04 FullContactRelief:  No*
G04 UndefLineWidth:     6.00*
G04 ================== end FILE IDENTIFICATION RECORD ====================*
%FSLAX35Y35*MOIN*%
%IR0*IPPOS*OFA0.00000B0.00000*MIA0B0*SFA1.00000B1.00000*%
%ADD10C,.006*%
G75*
%LPD*%
G75*
G54D10*
G01X85820Y-19685D02*
X-29308D01*
G01X-43308Y-5685D02*
G03X-29308Y-19685I14000J0D01*
G01X0Y3937D02*
Y106969D01*
G01Y3937D02*
Y106969D01*
G01X636457Y0D02*
X3937D01*
G01X636457D02*
X3937D01*
G01X0Y3937D02*
G03X3937Y0I3937J0D01*
G01X0Y3937D02*
G03X3937Y0I3937J0D01*
G01X-43308Y-5685D02*
Y103032D01*
G01X-7874Y50259D02*
Y3937D01*
G01D02*
G03X3937Y-7874I11811J0D01*
G01D02*
X77283D01*
G01X-7874Y103032D02*
Y75456D01*
G01Y75460D02*
G03X0I3937J0D01*
G01Y50259D02*
G03X-7874I-3937J0D01*
G01X-43307Y286142D02*
Y116811D01*
G01D02*
X-37402Y110906D01*
G01X-41339Y114843D02*
X-37402Y110906D01*
G01D02*
X-3937D01*
G01X-37402D02*
X-3937D01*
G01X0Y106969D02*
G03X-3937Y110906I-3937J0D01*
G01X0Y106969D02*
G03X-3937Y110906I-3937J0D01*
G01X-43308Y103032D02*
X-7874D01*
G01X-43307Y360039D02*
Y300709D01*
G01X-37402Y292047D02*
X-41339Y288110D01*
G01X-37402Y292047D02*
X-43307Y286142D01*
G01Y300709D02*
X-37402Y294803D01*
G01X-41339Y298740D02*
X-37402Y294803D01*
G01X-12598Y292047D02*
X-37402D01*
G01D02*
X-1378D01*
G01X-12598D02*
X-1378D01*
G01X-37402Y294803D02*
X-1378D01*
G01X-37402D02*
X-1378D01*
G01Y292047D02*
G03Y294803I0J1378D01*
G01Y292047D02*
G03Y294803I0J1378D01*
G01X-37402Y365945D02*
X-41339Y362008D01*
G01X-37402Y365945D02*
X-43307Y360039D01*
G01X0Y369882D02*
Y468504D01*
G01Y369882D02*
Y468504D01*
G01X-3937Y365945D02*
X-37402D01*
G01X-3937D02*
X-37402D01*
G01X-3937D02*
G03X0Y369882I0J3937D01*
G01X-3937Y365945D02*
G03X0Y369882I0J3937D01*
G01X-7874Y401397D02*
Y373819D01*
G01D02*
X-43307D01*
G01D02*
X-43308Y373820D01*
G01D02*
Y583347D01*
G01X0Y401397D02*
G03X-7874I-3937J0D01*
G01Y426594D02*
G03X0I3937J0D01*
G01X-7874D02*
Y530574D01*
G01X3937Y472441D02*
X636457D01*
G01X3937D02*
X636457D01*
G01X3937D02*
G03X0Y468504I0J-3937D01*
G01X3937Y472441D02*
G03X0Y468504I0J-3937D01*
G01Y484252D02*
Y587283D01*
G01Y484252D02*
Y587283D01*
G01X636457Y480315D02*
X3937D01*
G01X636457D02*
X3937D01*
G01X0Y484252D02*
G03X3937Y480315I3937J0D01*
G01X0Y484252D02*
G03X3937Y480315I3937J0D01*
G01X-7874Y583347D02*
Y555771D01*
G01D02*
G03X0I3937J0D01*
G01Y530574D02*
G03X-7874I-3937J0D01*
G01X-43307Y766457D02*
Y597126D01*
G01D02*
X-37402Y591220D01*
G01X-41339Y595157D02*
X-37402Y591220D01*
G01D02*
X-3937D01*
G01X-37402D02*
X-3937D01*
G01X0Y587283D02*
G03X-3937Y591220I-3937J0D01*
G01X0Y587283D02*
G03X-3937Y591220I-3937J0D01*
G01X-43308Y583347D02*
X-7874D01*
G01X-43307Y840354D02*
Y781024D01*
G01X-37402Y772362D02*
X-41339Y768425D01*
G01X-37402Y772362D02*
X-43307Y766457D01*
G01Y781024D02*
X-37402Y775118D01*
G01X-41339Y779055D02*
X-37402Y775118D01*
G01X-12598Y772362D02*
X-37402D01*
G01D02*
X-1378D01*
G01X-12598D02*
X-1378D01*
G01X-37402Y775118D02*
X-1378D01*
G01X-37402D02*
X-1378D01*
G01Y772362D02*
G03Y775118I0J1378D01*
G01Y772362D02*
G03Y775118I0J1378D01*
G01X-37402Y846260D02*
X-41339Y842323D01*
G01X-37402Y846260D02*
X-43307Y840354D01*
G01X0Y850197D02*
Y948819D01*
G01Y850197D02*
Y948819D01*
G01X-3937Y846260D02*
X-37402D01*
G01X-3937D02*
X-37402D01*
G01X-3937D02*
G03X0Y850197I0J3937D01*
G01X-3937Y846260D02*
G03X0Y850197I0J3937D01*
G01X-7874Y881712D02*
Y854134D01*
G01D02*
X-43308D01*
G01D02*
Y958441D01*
G01X0Y881711D02*
G03X-7874I-3937J0D01*
G01X3937Y952756D02*
X636457D01*
G01X3937D02*
X636457D01*
G01X3937D02*
G03X0Y948819I0J-3937D01*
G01X3937Y952756D02*
G03X0Y948819I0J-3937D01*
G01X-29308Y972441D02*
G03X-43308Y958441I0J-14000D01*
G01X-7874Y906909D02*
G03X0I3937J0D01*
G01X-7874D02*
Y948819D01*
G01X3937Y960630D02*
G03X-7874Y948819I0J-11811D01*
G01X-29308Y972441D02*
X1317968D01*
G01X3937Y960630D02*
X77283D01*
G01X17244Y226378D02*
Y246063D01*
G01X29055D02*
Y226378D01*
G01X25118Y222441D02*
X21181D01*
G01Y250000D02*
X25118D01*
G01X17244Y226378D02*
G03X21181Y222441I3937J0D01*
G01X25118D02*
G03X29055Y226378I0J3937D01*
G01Y246063D02*
G03X25118Y250000I-3937J0D01*
G01X21181D02*
G03X17244Y246063I0J-3937D01*
G01Y706693D02*
Y726378D01*
G01X29055D02*
Y706693D01*
G01X25118Y702756D02*
X21181D01*
G01Y730315D02*
X25118D01*
G01X17244Y706693D02*
G03X21181Y702756I3937J0D01*
G01X25118D02*
G03X29055Y706693I0J3937D01*
G01Y726378D02*
G03X25118Y730315I-3937J0D01*
G01X21181D02*
G03X17244Y726378I0J-3937D01*
G01X93694Y-19685D02*
X1317968D01*
G01X93694D02*
G03X85820I-3937J0D01*
G01X107993Y-7874D02*
X304843D01*
G01X107993Y0D02*
G03Y-7874I0J-3937D01*
G01X77283D02*
G03Y0I0J3937D01*
G01X107993Y480315D02*
G03Y472441I0J-3937D01*
G01X77283D02*
G03Y480315I0J3937D01*
G01X107993Y960630D02*
G03Y952756I0J-3937D01*
G01X77283D02*
G03Y960630I0J3937D01*
G01X107993D02*
X304843D01*
G01X335552Y-7874D02*
X532402D01*
G01X304843D02*
G03Y0I0J3937D01*
G01X335552D02*
G03Y-7874I0J-3937D01*
G01Y480315D02*
G03Y472441I0J-3937D01*
G01X304843D02*
G03Y480315I0J3937D01*
G01Y952756D02*
G03Y960630I0J3937D01*
G01X335552D02*
G03Y952756I0J-3937D01*
G01Y960630D02*
X532402D01*
G01X563111Y-7874D02*
X725552D01*
G01X563111Y0D02*
G03Y-7874I0J-3937D01*
G01X532402D02*
G03Y0I0J3937D01*
G01X627391Y353740D02*
X545906D01*
G01X627391D02*
X545906D01*
G01X627391Y378543D02*
X545906D01*
G01X627391D02*
X545906D01*
G01X541969Y357677D02*
Y374606D01*
G01Y357677D02*
Y374606D01*
G01X545906Y378543D02*
G03X541969Y374606I0J-3937D01*
G01Y357677D02*
G03X545906Y353740I3937J0D01*
G01X541969Y357677D02*
G03X545906Y353740I3937J0D01*
G01Y378543D02*
G03X541969Y374606I0J-3937D01*
G01X563111Y480315D02*
G03Y472441I0J-3937D01*
G01X532402D02*
G03Y480315I0J3937D01*
G01X627391Y834055D02*
X545906D01*
G01X627391D02*
X545906D01*
G01X541969Y837992D02*
Y854921D01*
G01Y837992D02*
Y854921D01*
G01Y837992D02*
G03X545906Y834055I3937J0D01*
G01X541969Y837992D02*
G03X545906Y834055I3937J0D01*
G01X627391Y858858D02*
X545906D01*
G01X627391D02*
X545906D01*
G01D02*
G03X541969Y854921I0J-3937D01*
G01X545906Y858858D02*
G03X541969Y854921I0J-3937D01*
G01X563111Y960630D02*
G03Y952756I0J-3937D01*
G01X532402D02*
G03Y960630I0J3937D01*
G01X563111D02*
X725552D01*
G01X636457Y132035D02*
X624646D01*
G01X636457D02*
X624646D01*
G01X620709Y135972D02*
Y312846D01*
G01Y135972D02*
Y312846D01*
G01Y135972D02*
G03X622708Y132545I3937J0D01*
G01X620709Y135972D02*
G03X622675Y132564I3937J0D01*
G01X622708Y132545D02*
G03X624646Y132035I1938J3427D01*
G01X622675Y132564D02*
G03X624646Y132035I1971J3409D01*
G01X620709Y135972D02*
Y312846D01*
G01Y135972D02*
Y312846D01*
G01Y135972D02*
G03X622708Y132545I3937J0D01*
G01X620709Y135972D02*
G03X622675Y132564I3937J0D01*
G01D02*
G03X624646Y132035I1971J3409D01*
G01X620709Y312657D02*
Y311161D01*
G01X636457Y316783D02*
X624646D01*
G01X636457D02*
X624646D01*
G01X622708Y316274D02*
G03X620709Y312846I1938J-3427D01*
G01X622675Y316255D02*
G03X620709Y312846I1971J-3408D01*
G01X624646Y316783D02*
G03X622708Y316274I-2J-3937D01*
G01X624646Y316783D02*
G03X622675Y316255I-1J-3937D01*
G01X622708Y316274D02*
G03X620709Y312846I1938J-3427D01*
G01X622675Y316255D02*
G03X620709Y312846I1971J-3408D01*
G01X624646Y316783D02*
G03X622675Y316255I-1J-3937D01*
G01X629574Y379204D02*
X638641Y385248D01*
G01X629574Y379204D02*
X638641Y385248D01*
G01Y347035D02*
X629574Y353079D01*
G01X638641Y347035D02*
X629574Y353079D01*
G01D02*
G03X627391Y353740I-2183J-3276D01*
G01X629574Y353079D02*
G03X627391Y353740I-2183J-3276D01*
G01Y378543D02*
G03X629574Y379205I-2J3937D01*
G01X627391Y378543D02*
G03X629574Y379205I-2J3937D01*
G01X636457Y612350D02*
X624646D01*
G01X636457D02*
X624646D01*
G01X620709Y616287D02*
Y793161D01*
G01Y616287D02*
Y793161D01*
G01Y616287D02*
G03X622708Y612860I3937J0D01*
G01X620709Y616287D02*
G03X622675Y612879I3937J0D01*
G01X622708Y612860D02*
G03X624646Y612350I1938J3427D01*
G01X622675Y612879D02*
G03X624646Y612350I1971J3409D01*
G01X638641Y827350D02*
X629574Y833394D01*
G01X638641Y827350D02*
X629574Y833394D01*
G01D02*
G03X627391Y834055I-2184J-3276D01*
G01X629574Y833394D02*
G03X627391Y834055I-2184J-3276D01*
G01X636457Y797098D02*
X624646D01*
G01X636457D02*
X624646D01*
G01X622708Y796589D02*
G03X620709Y793161I1938J-3427D01*
G01X622675Y796570D02*
G03X620709Y793161I1971J-3408D01*
G01X624646Y797098D02*
G03X622708Y796589I-2J-3937D01*
G01X624646Y797098D02*
G03X622675Y796570I-1J-3937D01*
G01X629574Y859520D02*
X638641Y865563D01*
G01X629574Y859520D02*
X638641Y865563D01*
G01X627391Y858858D02*
G03X629574Y859520I-2J3937D01*
G01X627391Y858858D02*
G03X629574Y859520I-2J3937D01*
G01X640394Y112350D02*
Y3937D01*
G01Y112350D02*
Y3937D01*
G01X636457Y0D02*
G03X640394Y3937I0J3937D01*
G01X636457Y0D02*
G03X640394Y3937I0J3937D01*
G01X1284723Y0D02*
X652203D01*
G01X1284723D02*
X652203D01*
G01X648266Y3937D02*
Y83917D01*
G01Y3937D02*
Y83917D01*
G01Y3937D02*
G03X652203Y0I3937J0D01*
G01X648266Y3937D02*
G03X652203Y0I3937J0D01*
G01X648267Y34437D02*
G03X640393I-3937J0D01*
G01X640394Y128098D02*
Y3937D01*
G01Y128098D02*
Y3937D01*
G01X659085Y93237D02*
X650019Y87193D01*
G01X659085Y93237D02*
X650019Y87193D01*
G01X661269Y93898D02*
X742754D01*
G01X661269D02*
X742754D01*
G01X650019Y87193D02*
G03X648266Y83917I2185J-3276D01*
G01X661269Y93898D02*
G03X659085Y93237I0J-3937D01*
G01X661269Y93898D02*
G03X659085Y93237I0J-3937D01*
G01X650019Y87193D02*
G03X648266Y83917I2185J-3276D01*
G01X640393Y65146D02*
G03X648267I3937J0D01*
G01X661269Y118701D02*
X742754D01*
G01X661269D02*
X742754D01*
G01X650019Y125406D02*
X659085Y119362D01*
G01X650019Y125406D02*
X659085Y119362D01*
G01D02*
G03X661269Y118701I2184J3276D01*
G01X648266Y128682D02*
G03X650019Y125406I3937J0D01*
G01X648266Y128682D02*
G03X650019Y125406I3937J0D01*
G01X659085Y119362D02*
G03X661269Y118701I2184J3276D01*
G01X640394Y128098D02*
G03X636457Y132035I-3937J0D01*
G01X640394Y128098D02*
G03X636457Y132035I-3937J0D01*
G01X652203Y155657D02*
X664014D01*
G01X652203D02*
X664014D01*
G01X667951Y336469D02*
Y159594D01*
G01Y336469D02*
Y159594D01*
G01X648266Y128682D02*
Y151720D01*
G01Y128682D02*
Y151720D01*
G01X665952Y156167D02*
G03X667951Y159594I-1938J3427D01*
G01X665985Y156186D02*
G03X667951Y159594I-1971J3408D01*
G01X664014Y155657D02*
G03X665952Y156167I0J3937D01*
G01X652203Y155657D02*
G03X648266Y151720I0J-3937D01*
G01X652203Y155657D02*
G03X648266Y151720I0J-3937D01*
G01X664014Y155657D02*
G03X665985Y156186I0J3938D01*
G01X640394Y343759D02*
Y320720D01*
G01Y343759D02*
Y320720D01*
G01X636457Y316783D02*
G03X640394Y320720I0J3937D01*
G01X636457Y316783D02*
G03X640394Y320720I0J3937D01*
G01Y468504D02*
Y388524D01*
G01Y468504D02*
Y388524D01*
G01Y343759D02*
G03X638641Y347035I-3938J0D01*
G01X640394Y343759D02*
G03X638641Y347035I-3938J0D01*
G01Y385248D02*
G03X640394Y388524I-2185J3276D01*
G01X638641Y385248D02*
G03X640394Y388524I-2185J3276D01*
G01X648266Y360091D02*
Y468504D01*
G01Y360091D02*
Y468504D01*
G01X652203Y340406D02*
X664014D01*
G01X652203D02*
X664014D01*
G01X648266Y344343D02*
Y468504D01*
G01Y344343D02*
Y468504D01*
G01X667951Y336469D02*
G03X665952Y339896I-3937J0D01*
G01X667951Y336469D02*
G03X665985Y339877I-3937J0D01*
G01X648266Y344343D02*
G03X652203Y340406I3937J0D01*
G01X665952Y339896D02*
G03X664014Y340406I-1938J-3427D01*
G01X648266Y344343D02*
G03X652203Y340406I3937J0D01*
G01X665985Y339877D02*
G03X664014Y340406I-1971J-3409D01*
G01X648267Y407295D02*
G03X640393I-3937J0D01*
G01Y438004D02*
G03X648267I3937J0D01*
G01X640394Y468504D02*
G03X636457Y472441I-3937J0D01*
G01X640394Y468504D02*
G03X636457Y472441I-3937J0D01*
G01X640394Y592665D02*
Y484252D01*
G01Y592665D02*
Y484252D01*
G01X636457Y480315D02*
G03X640394Y484252I0J3937D01*
G01X636457Y480315D02*
G03X640394Y484252I0J3937D01*
G01X1284723Y480315D02*
X652203D01*
G01X1284723D02*
X652203D01*
G01X648266Y484252D02*
Y564231D01*
G01Y484252D02*
Y564231D01*
G01Y484252D02*
G03X652203Y480315I3937J0D01*
G01X648266Y484252D02*
G03X652203Y480315I3937J0D01*
G01Y472441D02*
X1284723D01*
G01X652203D02*
X1284723D01*
G01X652203D02*
G03X648266Y468504I0J-3937D01*
G01X652203Y472441D02*
G03X648266Y468504I0J-3937D01*
G01X640394Y608413D02*
Y484252D01*
G01Y608413D02*
Y484252D01*
G01X640393Y545462D02*
G03X648267I3937J0D01*
G01Y514753D02*
G03X640393I-3937J0D01*
G01X659085Y573552D02*
X650019Y567507D01*
G01X659085Y573552D02*
X650019Y567507D01*
G01X661269Y599016D02*
X742754D01*
G01X661269D02*
X742754D01*
G01X661269Y574213D02*
X742754D01*
G01X661269D02*
X742754D01*
G01X650019Y605721D02*
X659085Y599677D01*
G01X650019Y605721D02*
X659085Y599677D01*
G01D02*
G03X661269Y599016I2184J3276D01*
G01X648266Y608997D02*
G03X650019Y605721I3937J0D01*
G01X648266Y608997D02*
G03X650019Y605721I3937J0D01*
G01X659085Y599677D02*
G03X661269Y599016I2184J3276D01*
G01X650019Y567507D02*
G03X648266Y564231I2184J-3276D01*
G01X661269Y574213D02*
G03X659085Y573552I0J-3937D01*
G01X661269Y574213D02*
G03X659085Y573552I0J-3937D01*
G01X650019Y567507D02*
G03X648266Y564231I2184J-3276D01*
G01X640394Y608413D02*
G03X636457Y612350I-3937J0D01*
G01X640394Y608413D02*
G03X636457Y612350I-3937J0D01*
G01X648266Y608997D02*
Y632035D01*
G01Y608997D02*
Y632035D01*
G01X652203Y635972D02*
X664014D01*
G01X652203D02*
X664014D01*
G01X667951Y816783D02*
Y639909D01*
G01Y816783D02*
Y639909D01*
G01X665952Y636482D02*
G03X667951Y639909I-1938J3427D01*
G01X665985Y636501D02*
G03X667951Y639909I-1971J3408D01*
G01X664014Y635972D02*
G03X665952Y636482I0J3937D01*
G01X652203Y635972D02*
G03X648266Y632035I0J-3937D01*
G01X652203Y635972D02*
G03X648266Y632035I0J-3937D01*
G01X664014Y635972D02*
G03X665985Y636501I0J3938D01*
G01X640394Y824074D02*
G03X638641Y827350I-3938J0D01*
G01X640394Y824074D02*
G03X638641Y827350I-3938J0D01*
G01X648266Y840406D02*
Y948819D01*
G01Y840406D02*
Y948819D01*
G01X640394Y824074D02*
Y801035D01*
G01Y824074D02*
Y801035D01*
G01X636457Y797098D02*
G03X640394Y801035I0J3937D01*
G01X636457Y797098D02*
G03X640394Y801035I0J3937D01*
G01X652203Y820720D02*
X664014D01*
G01X652203D02*
X664014D01*
G01X648266Y824657D02*
Y948819D01*
G01Y824657D02*
Y948819D01*
G01X667951Y816783D02*
G03X665952Y820211I-3937J1D01*
G01X667951Y816783D02*
G03X665985Y820192I-3937J1D01*
G01X648266Y824657D02*
G03X652203Y820720I3937J0D01*
G01X665952Y820211D02*
G03X664014Y820720I-1936J-3428D01*
G01X648266Y824657D02*
G03X652203Y820720I3937J0D01*
G01X665985Y820192D02*
G03X664014Y820720I-1970J-3409D01*
G01X640394Y948819D02*
Y868839D01*
G01Y948819D02*
Y868839D01*
G01X638641Y865563D02*
G03X640394Y868839I-2185J3276D01*
G01X638641Y865563D02*
G03X640394Y868839I-2185J3276D01*
G01X648267Y887611D02*
G03X640393I-3937J0D01*
G01X640394Y948819D02*
G03X636457Y952756I-3937J0D01*
G01X640394Y948819D02*
G03X636457Y952756I-3937J0D01*
G01X652203D02*
X1284723D01*
G01X652203D02*
X1284723D01*
G01X652203D02*
G03X648266Y948819I0J-3937D01*
G01X652203Y952756D02*
G03X648266Y948819I0J-3937D01*
G01X640393Y918320D02*
G03X648267I3937J0D01*
G01X725552Y-7874D02*
G03Y0I0J3937D01*
G01X746691Y114764D02*
Y97835D01*
G01Y114764D02*
Y97835D01*
G01X742754Y93898D02*
G03X746691Y97835I0J3937D01*
G01X742754Y93898D02*
G03X746691Y97835I0J3937D01*
G01Y114764D02*
G03X742754Y118701I-3937J0D01*
G01X746691Y114764D02*
G03X742754Y118701I-3937J0D01*
G01X725552Y472441D02*
G03Y480315I0J3937D01*
G01X746691Y595079D02*
Y578150D01*
G01Y595079D02*
Y578150D01*
G01X742754Y574213D02*
G03X746691Y578150I0J3937D01*
G01Y595079D02*
G03X742754Y599016I-3937J0D01*
G01X746691Y595079D02*
G03X742754Y599016I-3937J0D01*
G01Y574213D02*
G03X746691Y578150I0J3937D01*
G01X725552Y952756D02*
G03Y960630I0J3937D01*
G01X756261Y0D02*
G03Y-7874I0J-3937D01*
G01X953111D02*
X756261D01*
G01Y480315D02*
G03Y472441I0J-3937D01*
G01Y960630D02*
G03Y952756I0J-3937D01*
G01X953111Y960630D02*
X756261D01*
G01X953111Y-7874D02*
G03Y0I0J3937D01*
G01Y472441D02*
G03Y480315I0J3937D01*
G01Y952756D02*
G03Y960630I0J3937D01*
G01X983820Y0D02*
G03Y-7874I0J-3937D01*
G01X1180670D02*
X983820D01*
G01Y480315D02*
G03Y472441I0J-3937D01*
G01Y960630D02*
G03Y952756I0J-3937D01*
G01X1180670Y960630D02*
X983820D01*
G01X1180670Y-7874D02*
G03Y0I0J3937D01*
G01Y472441D02*
G03Y480315I0J3937D01*
G01Y952756D02*
G03Y960630I0J3937D01*
G01X1211380Y-7874D02*
X1284723D01*
G01X1211380Y0D02*
G03Y-7874I0J-3937D01*
G01X1259605Y226378D02*
Y246063D01*
G01X1263542Y250000D02*
G03X1259605Y246063I0J-3937D01*
G01Y226378D02*
G03X1263542Y222441I3937J0D01*
G01X1211380Y480315D02*
G03Y472441I0J-3937D01*
G01X1259605Y706693D02*
Y726378D01*
G01X1263542Y730315D02*
G03X1259605Y726378I0J-3937D01*
G01Y706693D02*
G03X1263542Y702756I3937J0D01*
G01X1211380Y960630D02*
G03Y952756I0J-3937D01*
G01Y960630D02*
X1284723D01*
G01X1317968Y-19685D02*
G03X1331968Y-5685I0J14000D01*
G01X1288660Y102559D02*
Y3937D01*
G01Y102559D02*
Y3937D01*
G01X1284723Y0D02*
G03X1288660Y3937I0J3937D01*
G01X1284723Y0D02*
G03X1288660Y3937I0J3937D01*
G01X1284723Y-7874D02*
G03X1296534Y3937I0J11811D01*
G01D02*
Y45847D01*
G01D02*
G03X1288660I-3937J0D01*
G01X1292597Y106496D02*
G03X1288660Y102559I0J-3937D01*
G01X1292597Y106496D02*
G03X1288660Y102559I0J-3937D01*
G01X1331968Y98622D02*
X1296534D01*
G01D02*
Y71044D01*
G01X1288660D02*
G03X1296534I3937J0D01*
G01X1292597Y106496D02*
X1326061D01*
G01X1292597D02*
X1326061D01*
G01X1301258Y180394D02*
X1326061D01*
G01D02*
X1290038D01*
G01X1301258D02*
X1290038D01*
G01X1326061Y177638D02*
X1290038D01*
G01X1326061D02*
X1290038D01*
G01Y180394D02*
G03Y177638I0J-1378D01*
G01Y180394D02*
G03Y177638I0J-1378D01*
G01X1271416Y246063D02*
Y226378D01*
G01X1263542Y250000D02*
X1267479D01*
G01Y222441D02*
X1263542D01*
G01X1271416Y246063D02*
G03X1267479Y250000I-3937J0D01*
G01Y222441D02*
G03X1271416Y226378I0J3937D01*
G01X1288660Y468504D02*
Y365472D01*
G01Y468504D02*
Y365472D01*
G01X1326061Y361535D02*
X1292597D01*
G01X1326061D02*
X1292597D01*
G01X1288660Y365472D02*
G03X1292597Y361535I3937J0D01*
G01X1288660Y365472D02*
G03X1292597Y361535I3937J0D01*
G01X1331968Y369409D02*
X1296534D01*
G01D02*
Y396985D01*
G01D02*
G03X1288660I-3937J0D01*
G01X1296534Y526162D02*
Y422182D01*
G01X1288660D02*
G03X1296534I3937J0D01*
G01X1288660Y582874D02*
Y484252D01*
G01Y582874D02*
Y484252D01*
G01X1284723Y480315D02*
G03X1288660Y484252I0J3937D01*
G01X1284723Y480315D02*
G03X1288660Y484252I0J3937D01*
G01Y468504D02*
G03X1284723Y472441I-3937J0D01*
G01X1288660Y468504D02*
G03X1284723Y472441I-3937J0D01*
G01X1296534Y578937D02*
Y551359D01*
G01X1288660D02*
G03X1296534I3937J0D01*
G01Y526162D02*
G03X1288660I-3937J0D01*
G01X1292597Y586811D02*
X1326061D01*
G01X1292597D02*
X1326061D01*
G01X1292597D02*
G03X1288660Y582874I0J-3937D01*
G01X1292597Y586811D02*
G03X1288660Y582874I0J-3937D01*
G01X1331968Y578937D02*
X1296534D01*
G01X1301258Y660709D02*
X1326061D01*
G01D02*
X1290038D01*
G01X1301258D02*
X1290038D01*
G01X1326061Y657953D02*
X1290038D01*
G01X1326061D02*
X1290038D01*
G01Y660709D02*
G03Y657953I0J-1378D01*
G01Y660709D02*
G03Y657953I0J-1378D01*
G01X1271416Y726378D02*
Y706693D01*
G01X1263542Y730315D02*
X1267479D01*
G01Y702756D02*
X1263542D01*
G01X1271416Y726378D02*
G03X1267479Y730315I-3937J0D01*
G01Y702756D02*
G03X1271416Y706693I0J3937D01*
G01X1326061Y841850D02*
X1292597D01*
G01X1326061D02*
X1292597D01*
G01X1288660Y845787D02*
G03X1292597Y841850I3937J0D01*
G01X1288660Y845787D02*
G03X1292597Y841850I3937J0D01*
G01X1288660Y948819D02*
Y845787D01*
G01Y948819D02*
Y845787D01*
G01X1296534Y849724D02*
Y877300D01*
G01Y877296D02*
G03X1288660I-3937J0D01*
G01X1296534Y948819D02*
Y902497D01*
G01X1288660D02*
G03X1296534I3937J0D01*
G01X1331968Y849724D02*
X1296534D01*
G01X1288660Y948819D02*
G03X1284723Y952756I-3937J0D01*
G01X1288660Y948819D02*
G03X1284723Y952756I-3937J0D01*
G01X1296534Y948819D02*
G03X1284723Y960630I-11811J0D01*
G01X1331968Y958441D02*
G03X1317968Y972441I-14000J0D01*
G01X1331968Y-5685D02*
Y98622D01*
G01X1331967Y112402D02*
Y171732D01*
G01X1326061Y106496D02*
X1329998Y110433D01*
G01X1326061Y106496D02*
X1331967Y112402D01*
G01Y186299D02*
Y355630D01*
G01X1326061Y180394D02*
X1329998Y184331D01*
G01X1326061Y180394D02*
X1331967Y186299D01*
G01Y171732D02*
X1326061Y177638D01*
G01X1329998Y173701D02*
X1326061Y177638D01*
G01X1331967Y355630D02*
X1326061Y361535D01*
G01X1329998Y357598D02*
X1326061Y361535D01*
G01X1331968Y578937D02*
Y369409D01*
G01X1331967Y592717D02*
Y652047D01*
G01X1326061Y586811D02*
X1329998Y590748D01*
G01X1326061Y586811D02*
X1331967Y592717D01*
G01Y666614D02*
Y835945D01*
G01X1326061Y660709D02*
X1329998Y664646D01*
G01X1326061Y660709D02*
X1331967Y666614D01*
G01Y652047D02*
X1326061Y657953D01*
G01X1329998Y654016D02*
X1326061Y657953D01*
G01X1331967Y835945D02*
X1326061Y841850D01*
G01X1329998Y837913D02*
X1326061Y841850D01*
G01X1331968Y958441D02*
Y849724D01*
M02*
